FILE_TYPE = CONNECTIVITY;
{Allegro Design Entry HDL 17.4-2019 S026 (4007227) 1/17/2022}
"PAGE_NUMBER" = 146;
0"NC";
1"P12V_AUX\g";
2"GND\g";
3"GND\g";
4"P12V_AUX\g";
5"P3V3_AUX\g";
6"GND\g";
7"GND\g";
8"GND\g";
9"P12V_AUX\g";
10"GND\g";
11"GND\g";
12"P3V3_AUX\g";
13"GND\g";
14"P12V_AUX\g";
15"P3V3_AUX_DSC";
16"P3V3_AUX_DSC_G2";
17"P3V3_AUX_DSC_S1";
18"P3V3_AUX_DSC_VOL";
19"P3V3_AUX_DSC_G1";
20"P12V_AUX_DSC_G2";
21"P12V_AUX_DSC";
22"P12V_AUX_DSC_S1";
23"P12V_AUX_DSC_VOL";
24"P12V_AUX_DSC_G1";
25"GND\g";
26"GND\g";
%"P1V0_AUX"
"1","(-9175,5525)","0","pure_quanta_power","I1";
;
HDL_POWER"P12V_AUX"
CDS_LIB"pure_quanta_power";
"A"1;
%"MOSFET_PCH_GDS_ESD_PROTECTED"
"1","(-5750,4350)","5","pure_quanta","I10";
;
LOCATION"Q7000"
SEC"1"
PART_TYPE"SMLF"
VALUE"DMP2035U-7"
MATERIAL"EMPTY"
CDS_LIB"pure_quanta"
CDS_LMAN_SYM_OUTLINE"-125,150,125,-150"
SEC_TYPE""
NEEDS_NO_SIZE"TRUE"
PART_NUMBER"BAM20350002";
"S"
$PN"S"22;
"G"
$PN"G"24;
"D"
$PN"D"20;
%"Q_RES"
"2","(-8025,5075)","0","pure_quanta","I11";
;
LOCATION"R1007"
$SEC"1"
CDS_SEC"1"
WATTAGE"1/16W"
TOLERANCE"1%"
VALUE"2K"
MATERIAL"EMPTY"
PACK_TYPE"0402LF"
CDS_LIB"pure_quanta"
PART_NUMBER"CS22002FB07";
"A"
$PN"1"14;
"B"
$PN"2"24;
%"Q_RES"
"2","(-8025,3925)","0","pure_quanta","I12";
;
LOCATION"R1049"
$SEC"1"
CDS_SEC"1"
TOLERANCE"1%"
VALUE"1K"
WATTAGE"1/16W"
MATERIAL"EMPTY"
PACK_TYPE"0402LF"
CDS_LIB"pure_quanta"
PART_NUMBER"CS21002FB06";
"A"
$PN"1"24;
"B"
$PN"2"2;
%"UNIVERSAL_GND"
"1","(-8025,3425)","2","pure_quanta_power","I13";
;
CDS_LIB"pure_quanta_power"
HDL_POWER"GND";
"A"2;
%"Q_RES"
"2","(-5200,3950)","0","pure_quanta","I14";
;
LOCATION"R1474"
$SEC"1"
CDS_SEC"1"
VALUE"10K"
TOLERANCE"1%"
WATTAGE"1/16W"
PACK_TYPE"0402LF"
MATERIAL"EMPTY"
CDS_LIB"pure_quanta"
PART_NUMBER"CS31002FB08";
"A"
$PN"1"20;
"B"
$PN"2"3;
%"UNIVERSAL_GND"
"1","(-5200,3525)","2","pure_quanta_power","I15";
;
CDS_LIB"pure_quanta_power"
HDL_POWER"GND";
"A"3;
%"MOSFET_NCH_1D3S"
"1","(-4150,4375)","6","pure_quanta","I16";
;
LOCATION"Q7001"
$SEC"1"
CDS_SEC"1"
PART_TYPE"SMLF"
VALUE"PSMNR58-30YLH"
MATERIAL"EMPTY"
CDS_LIB"pure_quanta"
CDS_LMAN_SYM_OUTLINE"-150,200,150,-200"
NEEDS_NO_SIZE"TRUE"
PART_NUMBER"BAMNR580000";
"1"
$PN"1"26;
"4"
$PN"4"20;
"2"
$PN"2"26;
"5"
$PN"5"21;
"3"
$PN"3"26;
%"UNIVERSAL_GND"
"1","(-4150,3575)","2","pure_quanta_power","I17";
;
CDS_LIB"pure_quanta_power"
HDL_POWER"GND";
"A"26;
%"P1V0_AUX"
"1","(-4150,5850)","0","pure_quanta_power","I18";
;
HDL_POWER"P12V_AUX"
CDS_LIB"pure_quanta_power";
"A"4;
%"Q_RES"
"2","(-4150,5350)","0","pure_quanta","I19";
;
LOCATION"R1480"
$SEC"1"
CDS_SEC"1"
VALUE"10"
TOLERANCE"1%"
WATTAGE"2W"
MATERIAL"EMPTY"
PACK_TYPE"2512LF"
CDS_LIB"pure_quanta"
PART_NUMBER"CS0100AFR00";
"A"
$PN"1"4;
"B"
$PN"2"21;
%"Q_RES"
"2","(-9175,5050)","0","pure_quanta","I2";
;
LOCATION"R700"
$SEC"1"
CDS_SEC"1"
WATTAGE"1/16W"
TOLERANCE"1%"
VALUE"30K"
PACK_TYPE"0402LF"
MATERIAL"EMPTY"
CDS_LIB"pure_quanta"
PART_NUMBER"CS33002FB02";
"A"
$PN"1"1;
"B"
$PN"2"23;
%"Q_RES"
"2","(-4025,2475)","0","pure_quanta","I21";
;
LOCATION"R1481"
$SEC"1"
CDS_SEC"1"
WATTAGE"2W"
TOLERANCE"1%"
VALUE"10"
PACK_TYPE"2512LF"
MATERIAL"EMPTY"
CDS_LIB"pure_quanta"
PART_NUMBER"CS0100AFR00";
"A"
$PN"1"12;
"B"
$PN"2"15;
%"MOSFET_NCH_1D3S"
"1","(-4025,1500)","6","pure_quanta","I22";
;
LOCATION"Q7003"
$SEC"1"
CDS_SEC"1"
PART_TYPE"SMLF"
VALUE"PSMNR58-30YLH"
MATERIAL"EMPTY"
NEEDS_NO_SIZE"TRUE"
CDS_LMAN_SYM_OUTLINE"-150,200,150,-200"
CDS_LIB"pure_quanta"
PART_NUMBER"BAMNR580000";
"1"
$PN"1"25;
"4"
$PN"4"16;
"2"
$PN"2"25;
"5"
$PN"5"15;
"3"
$PN"3"25;
%"MOSFET_PCH_GDS_ESD_PROTECTED"
"1","(-5625,1475)","5","pure_quanta","I23";
;
LOCATION"Q7002"
$SEC"1"
CDS_SEC"1"
PART_TYPE"SMLF"
MATERIAL"EMPTY"
VALUE"DMP2035U-7"
NEEDS_NO_SIZE"TRUE"
CDS_LMAN_SYM_OUTLINE"-125,150,125,-150"
CDS_LIB"pure_quanta"
PART_NUMBER"BAM20350002";
"S"
$PN"S"17;
"G"
$PN"G"19;
"D"
$PN"D"16;
%"P1V0_AUX"
"1","(-7900,2650)","0","pure_quanta_power","I24";
;
HDL_POWER"P3V3_AUX"
CDS_LIB"pure_quanta_power";
"A"5;
%"SCHOTTKY_DUAL_12A_3C"
"1","(-7250,1450)","5","pure_quanta","I25";
;
LOCATION"U60"
$SEC"1"
CDS_SEC"1"
PART_TYPE"SMLF"
VALUE"BAT54CW"
MATERIAL"EMPTY"
NEEDS_NO_SIZE"TRUE"
CDS_LMAN_SYM_OUTLINE"-100,50,100,-50"
CDS_LIB"pure_quanta"
PART_NUMBER"BCBAT54CZ13";
"C"
$PN"3"17;
"B"
$PN"1"18;
"A"
$PN"2"0;
%"UNIVERSAL_GND"
"1","(-4025,700)","2","pure_quanta_power","I27";
;
CDS_LIB"pure_quanta_power"
HDL_POWER"GND";
"A"25;
%"Q_RES"
"2","(-5075,1075)","0","pure_quanta","I28";
;
LOCATION"R1475"
$SEC"1"
CDS_SEC"1"
PACK_TYPE"0402LF"
VALUE"10K"
TOLERANCE"1%"
WATTAGE"1/16W"
MATERIAL"EMPTY"
CDS_LIB"pure_quanta"
PART_NUMBER"CS31002FB08";
"A"
$PN"1"16;
"B"
$PN"2"6;
%"UNIVERSAL_GND"
"1","(-5075,650)","2","pure_quanta_power","I29";
;
CDS_LIB"pure_quanta_power"
HDL_POWER"GND";
"A"6;
%"Q_RES"
"2","(-9175,3900)","0","pure_quanta","I3";
;
LOCATION"R855"
$SEC"1"
CDS_SEC"1"
WATTAGE"1/16W"
MATERIAL"EMPTY"
TOLERANCE"1%"
VALUE"11.5K"
PACK_TYPE"0402LF"
CDS_LIB"pure_quanta"
PART_NUMBER"CS31152FB03";
"A"
$PN"1"23;
"B"
$PN"2"11;
%"Q_CAP"
"1","(-6750,950)","0","pure_quanta","I30";
;
LOCATION"C1114"
$SEC"1"
CDS_SEC"1"
VALUE"22UF"
VOLTAGE"16V"
TOLERANCE"20%"
PACK_TYPE"C0805"
MATERIAL"EMPTY"
CDS_LIB"pure_quanta"
PART_NUMBER"CH6223MEA00";
"B"
$PN"2"7;
"A"
$PN"1"17;
%"UNIVERSAL_GND"
"1","(-6750,600)","2","pure_quanta_power","I31";
;
CDS_LIB"pure_quanta_power"
HDL_POWER"GND";
"A"7;
%"UNIVERSAL_GND"
"1","(-7900,550)","2","pure_quanta_power","I33";
;
CDS_LIB"pure_quanta_power"
HDL_POWER"GND";
"A"8;
%"P1V0_AUX"
"1","(-9050,2650)","0","pure_quanta_power","I34";
;
HDL_POWER"P12V_AUX"
CDS_LIB"pure_quanta_power";
"A"9;
%"Q_RES"
"2","(-9050,2175)","0","pure_quanta","I35";
;
LOCATION"R896"
$SEC"1"
CDS_SEC"1"
TOLERANCE"1%"
WATTAGE"1/16W"
VALUE"30K"
MATERIAL"EMPTY"
PACK_TYPE"0402LF"
CDS_LIB"pure_quanta"
PART_NUMBER"CS33002FB02";
"A"
$PN"1"9;
"B"
$PN"2"18;
%"Q_RES"
"2","(-9050,1025)","0","pure_quanta","I36";
;
LOCATION"R954"
$SEC"1"
CDS_SEC"1"
TOLERANCE"1%"
PACK_TYPE"0402LF"
VALUE"11.5K"
WATTAGE"1/16W"
MATERIAL"EMPTY"
CDS_LIB"pure_quanta"
PART_NUMBER"CS31152FB03";
"A"
$PN"1"18;
"B"
$PN"2"10;
%"UNIVERSAL_GND"
"1","(-9050,550)","2","pure_quanta_power","I37";
;
CDS_LIB"pure_quanta_power"
HDL_POWER"GND";
"A"10;
%"Q_RES"
"2","(-7900,2200)","0","pure_quanta","I38";
;
LOCATION"R1052"
$SEC"1"
CDS_SEC"1"
WATTAGE"1/16W"
TOLERANCE"1%"
VALUE"1K"
MATERIAL"EMPTY"
PACK_TYPE"0402LF"
CDS_LIB"pure_quanta"
PART_NUMBER"CS21002FB06";
"A"
$PN"1"5;
"B"
$PN"2"19;
%"Q_RES"
"2","(-7900,1050)","0","pure_quanta","I39";
;
LOCATION"R1092"
$SEC"1"
CDS_SEC"1"
MATERIAL"EMPTY"
WATTAGE"1/16W"
VALUE"10M"
TOLERANCE"1%"
PACK_TYPE"0402LF"
CDS_LIB"pure_quanta"
PART_NUMBER"CS61002FB02";
"A"
$PN"1"19;
"B"
$PN"2"8;
%"UNIVERSAL_GND"
"1","(-9175,3425)","2","pure_quanta_power","I4";
;
CDS_LIB"pure_quanta_power"
HDL_POWER"GND";
"A"11;
%"P1V0_AUX"
"1","(-4025,2975)","0","pure_quanta_power","I40";
;
HDL_POWER"P3V3_AUX"
CDS_LIB"pure_quanta_power";
"A"12;
%"SCHOTTKY_DUAL_12A_3C"
"1","(-7375,4325)","5","pure_quanta","I5";
;
LOCATION"U57"
SEC"1"
VALUE"BAT54CW"
MATERIAL"EMPTY"
PART_TYPE"SMLF"
CDS_LMAN_SYM_OUTLINE"-100,50,100,-50"
CDS_LIB"pure_quanta"
SEC_TYPE""
NEEDS_NO_SIZE"TRUE"
PART_NUMBER"BCBAT54CZ13";
"C"
$PN"3"22;
"B"
$PN"1"23;
"A"
$PN"2"0;
%"Q_CAP"
"1","(-6875,3825)","0","pure_quanta","I6";
;
LOCATION"C1113"
$SEC"1"
CDS_SEC"1"
VALUE"22UF"
VOLTAGE"16V"
TOLERANCE"20%"
MATERIAL"EMPTY"
PACK_TYPE"C0805"
CDS_LIB"pure_quanta"
PART_NUMBER"CH6223MEA00";
"B"
$PN"2"13;
"A"
$PN"1"22;
%"UNIVERSAL_GND"
"1","(-6875,3475)","2","pure_quanta_power","I7";
;
CDS_LIB"pure_quanta_power"
HDL_POWER"GND";
"A"13;
%"P1V0_AUX"
"1","(-8025,5525)","0","pure_quanta_power","I9";
;
HDL_POWER"P12V_AUX"
CDS_LIB"pure_quanta_power";
"A"14;
END.
